(kicad_pcb
	(version 20221018)
	(generator pcbnew)
	(general
    (thickness 1.586)
  )
	(paper "A4")
	(title_block
    (date "2024-03-26")
    (rev "1.1.3")
		(comment 9 "footprints 78-86 of 146")
	)
	(layers
    (0 "F.Cu" signal)
    (1 "In1.Cu" power)
    (2 "In2.Cu" power)
    (31 "B.Cu" signal)
    (32 "B.Adhes" user "B.Adhesive")
    (33 "F.Adhes" user "F.Adhesive")
    (34 "B.Paste" user)
    (35 "F.Paste" user)
    (36 "B.SilkS" user "B.Silkscreen")
    (37 "F.SilkS" user "F.Silkscreen")
    (38 "B.Mask" user)
    (39 "F.Mask" user)
    (40 "Dwgs.User" user "User.Drawings")
    (41 "Cmts.User" user "User.Comments")
    (42 "Eco1.User" user "User.Eco1")
    (43 "Eco2.User" user "User.Eco2")
    (44 "Edge.Cuts" user)
    (45 "Margin" user)
    (46 "B.CrtYd" user "B.Courtyard")
    (47 "F.CrtYd" user "F.Courtyard")
    (48 "B.Fab" user)
    (49 "F.Fab" user)
  )
	(footprint "scalenode-cm4-baseboard-footprints:R_0402_1005Metric" (layer "B.Cu")
    (at 94.372 86.375 90)
    (descr "Resistor SMD 0402")
    (tags "resistor SMD 0402")
    (property "Author" "Antmicro")
    (property "License" "Apache-2.0")
    (property "MPN" "CR0402-FX-1002GLF")
    (property "Manufacturer" "Bourns")
    (property "Sheetfile" "interfaces.kicad_sch")
    (property "Sheetname" "Interfaces")
    (property "Tolerance" "1%")
    (property "Val" "10k")
    (property "ki_description" "10k resistor in 0402 package with 1% tolerance")
    (attr smd)
    (fp_text reference "R5" (at 3.2 0.403 270) (layer "B.SilkS")
        (effects (font (size 0.7 0.7) (thickness 0.15)) (justify left bottom mirror))
    )
    (fp_text value "R_10k_0402" (at 0 -1.4 270) (layer "B.Fab")
        (effects (font (size 0.7 0.7) (thickness 0.15)) (justify left bottom mirror))
    )
    (fp_text user "${REFERENCE}" (at -0.95 -3.168 270) (layer "B.Fab") hide
        (effects (font (size 0.7 0.7) (thickness 0.15)) (justify left bottom mirror))
    )
    (fp_text user "License: Apache-2.0" (at -0.95 -5.169 270) (layer "B.Fab") hide
        (effects (font (size 0.7 0.7) (thickness 0.15)) (justify left bottom mirror))
    )
    (fp_text user "Author: Antmicro" (at -0.95 -4.169 270) (layer "B.Fab") hide
        (effects (font (size 0.7 0.7) (thickness 0.15)) (justify left bottom mirror))
    )
    (fp_rect (start -0.95 0.48) (end 0.95 -0.48)
      (stroke (width 0.05) (type solid)) (fill none) (layer "B.CrtYd"))
    (fp_rect (start -0.5 0.25) (end 0.5 -0.25)
      (stroke (width 0.15) (type solid)) (fill none) (layer "B.Fab"))
    (pad "1" smd roundrect (at -0.485 0 90) (size 0.59 0.64) (layers "B.Cu" "B.Paste" "B.Mask") (roundrect_rratio 0.25)
      (net 232 "3V3_RPi") (pintype "passive"))
    (pad "2" smd roundrect (at 0.485 0 90) (size 0.59 0.64) (layers "B.Cu" "B.Paste" "B.Mask") (roundrect_rratio 0.25)
      (net 28 "SD_DAT1") (pintype "passive"))
  )
	(footprint "scalenode-cm4-baseboard-footprints:C_0603_1608Metric" (layer "B.Cu")
    (at 176.07 67.352 -90)
    (descr "Capacitor SMD 0603")
    (tags "capacitor 0603")
    (property "Author" "Antmicro")
    (property "Dielectric" "")
    (property "License" "Apache-2.0")
    (property "MPN" "0603YC104KAZ2A")
    (property "Manufacturer" "AVX")
    (property "Sheetfile" "nvme-ssd.kicad_sch")
    (property "Sheetname" "NVMe SSD")
    (property "Val" "100n")
    (property "Voltage" "")
    (property "ki_description" " ")
    (attr smd)
    (fp_text reference "C7" (at -3.143667 -0.405 90) (layer "B.SilkS")
        (effects (font (size 0.7 0.7) (thickness 0.15)) (justify left bottom mirror))
    )
    (fp_text value "C_100n_0603" (at 0 -1.6 90) (layer "B.Fab")
        (effects (font (size 0.7 0.7) (thickness 0.15)) (justify left bottom mirror))
    )
    (fp_text user "Author: Antmicro" (at -1.682 -4.894 90) (layer "B.Fab") hide
        (effects (font (size 0.7 0.7) (thickness 0.15)) (justify left bottom mirror))
    )
    (fp_text user "License: Apache-2.0" (at -1.682 -5.895 90) (layer "B.Fab") hide
        (effects (font (size 0.7 0.7) (thickness 0.15)) (justify left bottom mirror))
    )
    (fp_text user "${REFERENCE}" (at -1.682 -3.895 90) (layer "B.Fab") hide
        (effects (font (size 0.7 0.7) (thickness 0.15)) (justify left bottom mirror))
    )
    (fp_line (start -0.3 -0.3) (end 0.3 -0.3)
      (stroke (width 0.15) (type solid)) (layer "B.SilkS"))
    (fp_line (start -0.3 0.3) (end 0.3 0.3)
      (stroke (width 0.15) (type solid)) (layer "B.SilkS"))
    (fp_rect (start -1.24 0.7) (end 1.24 -0.7)
      (stroke (width 0.05) (type solid)) (fill none) (layer "B.CrtYd"))
    (fp_rect (start -0.8 0.4) (end 0.8 -0.4)
      (stroke (width 0.15) (type solid)) (fill none) (layer "B.Fab"))
    (pad "1" smd roundrect (at -0.7 0 270) (size 0.6 0.8) (layers "B.Cu" "B.Paste" "B.Mask") (roundrect_rratio 0.2)
      (net 11 "GND") (pintype "passive"))
    (pad "2" smd roundrect (at 0.7 0 270) (size 0.6 0.8) (layers "B.Cu" "B.Paste" "B.Mask") (roundrect_rratio 0.2)
      (net 170 "3V3_SSD") (pintype "passive"))
  )
	(footprint "scalenode-cm4-baseboard-footprints:C_0603_1608Metric" (layer "B.Cu")
    (at 173.022 81.068 -90)
    (descr "Capacitor SMD 0603")
    (tags "capacitor 0603")
    (property "Author" "Antmicro")
    (property "License" "Apache-2.0")
    (property "MPN" "GRM188R61A106KE69D")
    (property "Manufacturer" "Murata")
    (property "Sheetfile" "nvme-ssd.kicad_sch")
    (property "Sheetname" "NVMe SSD")
    (property "Val" "10u")
    (property "Voltage" "")
    (property "ki_description" " ")
    (attr smd)
    (fp_text reference "C2" (at -2.968 -0.503 90) (layer "B.SilkS")
        (effects (font (size 0.7 0.7) (thickness 0.15)) (justify left bottom mirror))
    )
    (fp_text value "C_10u_0603" (at 0 -1.6 90) (layer "B.Fab")
        (effects (font (size 0.7 0.7) (thickness 0.15)) (justify left bottom mirror))
    )
    (fp_text user "Author: Antmicro" (at -1.682 -4.894 90) (layer "B.Fab") hide
        (effects (font (size 0.7 0.7) (thickness 0.15)) (justify left bottom mirror))
    )
    (fp_text user "${REFERENCE}" (at -1.682 -3.895 90) (layer "B.Fab") hide
        (effects (font (size 0.7 0.7) (thickness 0.15)) (justify left bottom mirror))
    )
    (fp_text user "License: Apache-2.0" (at -1.682 -5.895 90) (layer "B.Fab") hide
        (effects (font (size 0.7 0.7) (thickness 0.15)) (justify left bottom mirror))
    )
    (fp_line (start -0.3 -0.3) (end 0.3 -0.3)
      (stroke (width 0.15) (type solid)) (layer "B.SilkS"))
    (fp_line (start -0.3 0.3) (end 0.3 0.3)
      (stroke (width 0.15) (type solid)) (layer "B.SilkS"))
    (fp_rect (start -1.24 0.7) (end 1.24 -0.7)
      (stroke (width 0.05) (type solid)) (fill none) (layer "B.CrtYd"))
    (fp_rect (start -0.8 0.4) (end 0.8 -0.4)
      (stroke (width 0.15) (type solid)) (fill none) (layer "B.Fab"))
    (pad "1" smd roundrect (at -0.7 0 270) (size 0.6 0.8) (layers "B.Cu" "B.Paste" "B.Mask") (roundrect_rratio 0.2)
      (net 11 "GND") (pintype "passive"))
    (pad "2" smd roundrect (at 0.7 0 270) (size 0.6 0.8) (layers "B.Cu" "B.Paste" "B.Mask") (roundrect_rratio 0.2)
      (net 170 "3V3_SSD") (pintype "passive"))
  )
	(footprint "scalenode-cm4-baseboard-footprints:C_0603_1608Metric" (layer "B.Cu")
    (at 177.594 86.148 90)
    (descr "Capacitor SMD 0603")
    (tags "capacitor 0603")
    (property "Author" "Antmicro")
    (property "Dielectric" "")
    (property "License" "Apache-2.0")
    (property "MPN" "06031C102JAT2A")
    (property "Manufacturer" "AVX")
    (property "Sheetfile" "nvme-ssd.kicad_sch")
    (property "Sheetname" "NVMe SSD")
    (property "Val" "1n")
    (property "Voltage" "")
    (property "ki_description" " ")
    (attr smd)
    (fp_text reference "C12" (at -3.502 0.456 90) (layer "B.SilkS")
        (effects (font (size 0.7 0.7) (thickness 0.15)) (justify right bottom mirror))
    )
    (fp_text value "C_1n_0603" (at 0 -1.6 90) (layer "B.Fab")
        (effects (font (size 0.7 0.7) (thickness 0.15)) (justify right bottom mirror))
    )
    (fp_text user "${REFERENCE}" (at -1.682 -3.895 90) (layer "B.Fab") hide
        (effects (font (size 0.7 0.7) (thickness 0.15)) (justify right bottom mirror))
    )
    (fp_text user "Author: Antmicro" (at -1.682 -4.894 90) (layer "B.Fab") hide
        (effects (font (size 0.7 0.7) (thickness 0.15)) (justify right bottom mirror))
    )
    (fp_text user "License: Apache-2.0" (at -1.682 -5.895 90) (layer "B.Fab") hide
        (effects (font (size 0.7 0.7) (thickness 0.15)) (justify right bottom mirror))
    )
    (fp_line (start -0.3 -0.3) (end 0.3 -0.3)
      (stroke (width 0.15) (type solid)) (layer "B.SilkS"))
    (fp_line (start -0.3 0.3) (end 0.3 0.3)
      (stroke (width 0.15) (type solid)) (layer "B.SilkS"))
    (fp_rect (start -1.24 0.7) (end 1.24 -0.7)
      (stroke (width 0.05) (type solid)) (fill none) (layer "B.CrtYd"))
    (fp_rect (start -0.8 0.4) (end 0.8 -0.4)
      (stroke (width 0.15) (type solid)) (fill none) (layer "B.Fab"))
    (pad "1" smd roundrect (at -0.7 0 90) (size 0.6 0.8) (layers "B.Cu" "B.Paste" "B.Mask") (roundrect_rratio 0.2)
      (net 11 "GND") (pintype "passive"))
    (pad "2" smd roundrect (at 0.7 0 90) (size 0.6 0.8) (layers "B.Cu" "B.Paste" "B.Mask") (roundrect_rratio 0.2)
      (net 170 "3V3_SSD") (pintype "passive"))
  )
	(footprint "scalenode-cm4-baseboard-footprints:C_0603_1608Metric" (layer "B.Cu")
    (at 176.07 81.068 -90)
    (descr "Capacitor SMD 0603")
    (tags "capacitor 0603")
    (property "Author" "Antmicro")
    (property "Dielectric" "")
    (property "License" "Apache-2.0")
    (property "MPN" "0603YC104KAZ2A")
    (property "Manufacturer" "AVX")
    (property "Sheetfile" "nvme-ssd.kicad_sch")
    (property "Sheetname" "NVMe SSD")
    (property "Val" "100n")
    (property "Voltage" "")
    (property "ki_description" " ")
    (attr smd)
    (fp_text reference "C8" (at -2.968 -0.355 90) (layer "B.SilkS")
        (effects (font (size 0.7 0.7) (thickness 0.15)) (justify left bottom mirror))
    )
    (fp_text value "C_100n_0603" (at 0 -1.6 90) (layer "B.Fab")
        (effects (font (size 0.7 0.7) (thickness 0.15)) (justify left bottom mirror))
    )
    (fp_text user "License: Apache-2.0" (at -1.682 -5.895 90) (layer "B.Fab") hide
        (effects (font (size 0.7 0.7) (thickness 0.15)) (justify left bottom mirror))
    )
    (fp_text user "Author: Antmicro" (at -1.682 -4.894 90) (layer "B.Fab") hide
        (effects (font (size 0.7 0.7) (thickness 0.15)) (justify left bottom mirror))
    )
    (fp_text user "${REFERENCE}" (at -1.682 -3.895 90) (layer "B.Fab") hide
        (effects (font (size 0.7 0.7) (thickness 0.15)) (justify left bottom mirror))
    )
    (fp_line (start -0.3 -0.3) (end 0.3 -0.3)
      (stroke (width 0.15) (type solid)) (layer "B.SilkS"))
    (fp_line (start -0.3 0.3) (end 0.3 0.3)
      (stroke (width 0.15) (type solid)) (layer "B.SilkS"))
    (fp_rect (start -1.24 0.7) (end 1.24 -0.7)
      (stroke (width 0.05) (type solid)) (fill none) (layer "B.CrtYd"))
    (fp_rect (start -0.8 0.4) (end 0.8 -0.4)
      (stroke (width 0.15) (type solid)) (fill none) (layer "B.Fab"))
    (pad "1" smd roundrect (at -0.7 0 270) (size 0.6 0.8) (layers "B.Cu" "B.Paste" "B.Mask") (roundrect_rratio 0.2)
      (net 11 "GND") (pintype "passive"))
    (pad "2" smd roundrect (at 0.7 0 270) (size 0.6 0.8) (layers "B.Cu" "B.Paste" "B.Mask") (roundrect_rratio 0.2)
      (net 170 "3V3_SSD") (pintype "passive"))
  )
	(footprint "scalenode-cm4-baseboard-footprints:C_0603_1608Metric" (layer "B.Cu")
    (at 174.546 81.068 -90)
    (descr "Capacitor SMD 0603")
    (tags "capacitor 0603")
    (property "Author" "Antmicro")
    (property "Dielectric" "")
    (property "License" "Apache-2.0")
    (property "MPN" "0603YD105KAT2A")
    (property "Manufacturer" "Walsin")
    (property "Sheetfile" "nvme-ssd.kicad_sch")
    (property "Sheetname" "NVMe SSD")
    (property "Val" "1u")
    (property "Voltage" "")
    (property "ki_description" " ")
    (attr smd)
    (fp_text reference "C5" (at -2.968 -0.379 90) (layer "B.SilkS")
        (effects (font (size 0.7 0.7) (thickness 0.15)) (justify left bottom mirror))
    )
    (fp_text value "C_1u_0603" (at 0 -1.6 90) (layer "B.Fab")
        (effects (font (size 0.7 0.7) (thickness 0.15)) (justify left bottom mirror))
    )
    (fp_text user "License: Apache-2.0" (at -1.682 -5.895 90) (layer "B.Fab") hide
        (effects (font (size 0.7 0.7) (thickness 0.15)) (justify left bottom mirror))
    )
    (fp_text user "${REFERENCE}" (at -1.682 -3.895 90) (layer "B.Fab") hide
        (effects (font (size 0.7 0.7) (thickness 0.15)) (justify left bottom mirror))
    )
    (fp_text user "Author: Antmicro" (at -1.682 -4.894 90) (layer "B.Fab") hide
        (effects (font (size 0.7 0.7) (thickness 0.15)) (justify left bottom mirror))
    )
    (fp_line (start -0.3 -0.3) (end 0.3 -0.3)
      (stroke (width 0.15) (type solid)) (layer "B.SilkS"))
    (fp_line (start -0.3 0.3) (end 0.3 0.3)
      (stroke (width 0.15) (type solid)) (layer "B.SilkS"))
    (fp_rect (start -1.24 0.7) (end 1.24 -0.7)
      (stroke (width 0.05) (type solid)) (fill none) (layer "B.CrtYd"))
    (fp_rect (start -0.8 0.4) (end 0.8 -0.4)
      (stroke (width 0.15) (type solid)) (fill none) (layer "B.Fab"))
    (pad "1" smd roundrect (at -0.7 0 270) (size 0.6 0.8) (layers "B.Cu" "B.Paste" "B.Mask") (roundrect_rratio 0.2)
      (net 11 "GND") (pintype "passive"))
    (pad "2" smd roundrect (at 0.7 0 270) (size 0.6 0.8) (layers "B.Cu" "B.Paste" "B.Mask") (roundrect_rratio 0.2)
      (net 170 "3V3_SSD") (pintype "passive"))
  )
	(footprint "scalenode-cm4-baseboard-footprints:C_0603_1608Metric" (layer "B.Cu")
    (at 177.594 81.068 -90)
    (descr "Capacitor SMD 0603")
    (tags "capacitor 0603")
    (property "Author" "Antmicro")
    (property "Dielectric" "")
    (property "License" "Apache-2.0")
    (property "MPN" "06031C102JAT2A")
    (property "Manufacturer" "AVX")
    (property "Sheetfile" "nvme-ssd.kicad_sch")
    (property "Sheetname" "NVMe SSD")
    (property "Val" "1n")
    (property "Voltage" "")
    (property "ki_description" " ")
    (attr smd)
    (fp_text reference "C11" (at -3.301333 -0.356 90) (layer "B.SilkS")
        (effects (font (size 0.7 0.7) (thickness 0.15)) (justify left bottom mirror))
    )
    (fp_text value "C_1n_0603" (at 0 -1.6 90) (layer "B.Fab")
        (effects (font (size 0.7 0.7) (thickness 0.15)) (justify left bottom mirror))
    )
    (fp_text user "${REFERENCE}" (at -1.682 -3.895 90) (layer "B.Fab") hide
        (effects (font (size 0.7 0.7) (thickness 0.15)) (justify left bottom mirror))
    )
    (fp_text user "Author: Antmicro" (at -1.682 -4.894 90) (layer "B.Fab") hide
        (effects (font (size 0.7 0.7) (thickness 0.15)) (justify left bottom mirror))
    )
    (fp_text user "License: Apache-2.0" (at -1.682 -5.895 90) (layer "B.Fab") hide
        (effects (font (size 0.7 0.7) (thickness 0.15)) (justify left bottom mirror))
    )
    (fp_line (start -0.3 -0.3) (end 0.3 -0.3)
      (stroke (width 0.15) (type solid)) (layer "B.SilkS"))
    (fp_line (start -0.3 0.3) (end 0.3 0.3)
      (stroke (width 0.15) (type solid)) (layer "B.SilkS"))
    (fp_rect (start -1.24 0.7) (end 1.24 -0.7)
      (stroke (width 0.05) (type solid)) (fill none) (layer "B.CrtYd"))
    (fp_rect (start -0.8 0.4) (end 0.8 -0.4)
      (stroke (width 0.15) (type solid)) (fill none) (layer "B.Fab"))
    (pad "1" smd roundrect (at -0.7 0 270) (size 0.6 0.8) (layers "B.Cu" "B.Paste" "B.Mask") (roundrect_rratio 0.2)
      (net 11 "GND") (pintype "passive"))
    (pad "2" smd roundrect (at 0.7 0 270) (size 0.6 0.8) (layers "B.Cu" "B.Paste" "B.Mask") (roundrect_rratio 0.2)
      (net 170 "3V3_SSD") (pintype "passive"))
  )
	(footprint "scalenode-cm4-baseboard-footprints:C_0603_1608Metric" (layer "B.Cu")
    (at 173.022 86.148 90)
    (descr "Capacitor SMD 0603")
    (tags "capacitor 0603")
    (property "Author" "Antmicro")
    (property "License" "Apache-2.0")
    (property "MPN" "GRM188R61A106KE69D")
    (property "Manufacturer" "Murata")
    (property "Sheetfile" "nvme-ssd.kicad_sch")
    (property "Sheetname" "NVMe SSD")
    (property "Val" "10u")
    (property "Voltage" "")
    (property "ki_description" " ")
    (attr smd)
    (fp_text reference "C3" (at -3.168667 0.353 90) (layer "B.SilkS")
        (effects (font (size 0.7 0.7) (thickness 0.15)) (justify right bottom mirror))
    )
    (fp_text value "C_10u_0603" (at 0 -1.6 90) (layer "B.Fab")
        (effects (font (size 0.7 0.7) (thickness 0.15)) (justify right bottom mirror))
    )
    (fp_text user "Author: Antmicro" (at -1.682 -4.894 90) (layer "B.Fab") hide
        (effects (font (size 0.7 0.7) (thickness 0.15)) (justify right bottom mirror))
    )
    (fp_text user "License: Apache-2.0" (at -1.682 -5.895 90) (layer "B.Fab") hide
        (effects (font (size 0.7 0.7) (thickness 0.15)) (justify right bottom mirror))
    )
    (fp_text user "${REFERENCE}" (at -1.682 -3.895 90) (layer "B.Fab") hide
        (effects (font (size 0.7 0.7) (thickness 0.15)) (justify right bottom mirror))
    )
    (fp_line (start -0.3 -0.3) (end 0.3 -0.3)
      (stroke (width 0.15) (type solid)) (layer "B.SilkS"))
    (fp_line (start -0.3 0.3) (end 0.3 0.3)
      (stroke (width 0.15) (type solid)) (layer "B.SilkS"))
    (fp_rect (start -1.24 0.7) (end 1.24 -0.7)
      (stroke (width 0.05) (type solid)) (fill none) (layer "B.CrtYd"))
    (fp_rect (start -0.8 0.4) (end 0.8 -0.4)
      (stroke (width 0.15) (type solid)) (fill none) (layer "B.Fab"))
    (pad "1" smd roundrect (at -0.7 0 90) (size 0.6 0.8) (layers "B.Cu" "B.Paste" "B.Mask") (roundrect_rratio 0.2)
      (net 11 "GND") (pintype "passive"))
    (pad "2" smd roundrect (at 0.7 0 90) (size 0.6 0.8) (layers "B.Cu" "B.Paste" "B.Mask") (roundrect_rratio 0.2)
      (net 170 "3V3_SSD") (pintype "passive"))
  )
	(footprint "scalenode-cm4-baseboard-footprints:C_0603_1608Metric" (layer "B.Cu")
    (at 177.594 67.352 -90)
    (descr "Capacitor SMD 0603")
    (tags "capacitor 0603")
    (property "Author" "Antmicro")
    (property "Dielectric" "")
    (property "License" "Apache-2.0")
    (property "MPN" "06031C102JAT2A")
    (property "Manufacturer" "AVX")
    (property "Sheetfile" "nvme-ssd.kicad_sch")
    (property "Sheetname" "NVMe SSD")
    (property "Val" "1n")
    (property "Voltage" "")
    (property "ki_description" " ")
    (attr smd)
    (fp_text reference "C10" (at -3.477 -0.356 90) (layer "B.SilkS")
        (effects (font (size 0.7 0.7) (thickness 0.15)) (justify left bottom mirror))
    )
    (fp_text value "C_1n_0603" (at 0 -1.6 90) (layer "B.Fab")
        (effects (font (size 0.7 0.7) (thickness 0.15)) (justify left bottom mirror))
    )
    (fp_text user "${REFERENCE}" (at -1.682 -3.895 90) (layer "B.Fab") hide
        (effects (font (size 0.7 0.7) (thickness 0.15)) (justify left bottom mirror))
    )
    (fp_text user "License: Apache-2.0" (at -1.682 -5.895 90) (layer "B.Fab") hide
        (effects (font (size 0.7 0.7) (thickness 0.15)) (justify left bottom mirror))
    )
    (fp_text user "Author: Antmicro" (at -1.682 -4.894 90) (layer "B.Fab") hide
        (effects (font (size 0.7 0.7) (thickness 0.15)) (justify left bottom mirror))
    )
    (fp_line (start -0.3 -0.3) (end 0.3 -0.3)
      (stroke (width 0.15) (type solid)) (layer "B.SilkS"))
    (fp_line (start -0.3 0.3) (end 0.3 0.3)
      (stroke (width 0.15) (type solid)) (layer "B.SilkS"))
    (fp_rect (start -1.24 0.7) (end 1.24 -0.7)
      (stroke (width 0.05) (type solid)) (fill none) (layer "B.CrtYd"))
    (fp_rect (start -0.8 0.4) (end 0.8 -0.4)
      (stroke (width 0.15) (type solid)) (fill none) (layer "B.Fab"))
    (pad "1" smd roundrect (at -0.7 0 270) (size 0.6 0.8) (layers "B.Cu" "B.Paste" "B.Mask") (roundrect_rratio 0.2)
      (net 11 "GND") (pintype "passive"))
    (pad "2" smd roundrect (at 0.7 0 270) (size 0.6 0.8) (layers "B.Cu" "B.Paste" "B.Mask") (roundrect_rratio 0.2)
      (net 170 "3V3_SSD") (pintype "passive"))
  )
)
